# T6G (Grand Teton) — schematic netlist excerpt (pin names and nets, part order shuffled) for the footprints in the layout excerpt that follows; sources: Cadence DE-HDL packaged netlist, KiCad conversion of 04192023_DAF0TMB3IC0_F0TG_MB_C_brd_V02_OCP.brd

R851  Q_RES  0 5% CHIP  pkg 0201LF  page 185 : A = SMB_MUX_RT_ROM_SCL ; B = SMB_MUX_RT_ROM_R1_SCL
R1676  Q_RES  10 1% CHIP  pkg 0402LF  page 89 : A = I3C_SPD_DDRAF_CPU0_SDA ; B = I3C_SPD_DDRD_CPU0_SDA
R3227  Q_RES  2.2K 5% EMPTY  pkg 0402LF  page 151 : A = SMB_1_BMC_GPU_SDA ; B = P3V3_AUX

(kicad_pcb
	(version 20260206)
	(generator "pcbnew")
	(generator_version "10.0")
	(general
		(thickness 1.6)
		(legacy_teardrops no)
	)
	(paper "A4")
	(title_block
		(title "04192023_DAF0TMB3IC0_F0TG_MB_C_brd_V02_OCP.brd")
		(comment 1 "Grand Teton / footprints 5539-5541 of 8354")
	)
	(layers
		(0 "F.Cu" signal "TOP")
		(4 "In1.Cu" signal "GND")
		(6 "In2.Cu" signal "IN1")
		(8 "In3.Cu" signal "GND1")
		(10 "In4.Cu" signal "IN2")
		(12 "In5.Cu" signal "GND2")
		(14 "In6.Cu" signal "IN3")
		(16 "In7.Cu" signal "GND3")
		(18 "In8.Cu" signal "VCC")
		(20 "In9.Cu" signal "VCC1")
		(22 "In10.Cu" signal "GND4")
		(24 "In11.Cu" signal "IN4")
		(26 "In12.Cu" signal "GND5")
		(28 "In13.Cu" signal "IN5")
		(30 "In14.Cu" signal "GND6")
		(32 "In15.Cu" signal "IN6")
		(34 "In16.Cu" signal "GND7")
		(2 "B.Cu" signal "BOTTOM")
		(9 "F.Adhes" user "F.Adhesive")
		(11 "B.Adhes" user "B.Adhesive")
		(13 "F.Paste" user "Package Geometry/Pastemask Top")
		(15 "B.Paste" user "Package Geometry/Pastemask Bottom")
		(5 "F.SilkS" user "Ref Des/Silkscreen Top")
		(7 "B.SilkS" user "Ref Des/Silkscreen Bottom")
		(1 "F.Mask" user "Board Geometry/Soldermask Top")
		(3 "B.Mask" user "Board Geometry/Soldermask Bottom")
		(17 "Dwgs.User" user "User.Drawings")
		(19 "Cmts.User" user "User.Comments")
		(21 "Eco1.User" user "User.Eco1")
		(23 "Eco2.User" user "User.Eco2")
		(25 "Edge.Cuts" user "Board Geometry/Outline")
		(27 "Margin" user)
		(31 "F.CrtYd" user "Package Geometry/Place Bound Top")
		(29 "B.CrtYd" user "Package Geometry/Place Bound Bottom")
		(35 "F.Fab" user "Ref Des/Assembly Top")
		(33 "B.Fab" user "Ref Des/Assembly Bottom")
	)
	(footprint ""
		(layer "B.Cu")
		(at 254.635 -331.978 180)
		(property "Reference" "R851"
			(at 0 0 0)
			(layer "B.SilkS")
			(hide yes)
			(effects
				(font
					(size 1.27 1.27)
				)
				(justify mirror)
			)
		)
		(property "Value" ""
			(at 0 0 0)
			(layer "B.Fab")
			(effects
				(font
					(size 1.27 1.27)
				)
				(justify mirror)
			)
		)
		(duplicate_pad_numbers_are_jumpers no)
		(fp_line
			(start 0.32512 0.175006)
			(end 0.32512 -0.175006)
			(stroke
				(width 0.1)
				(type default)
			)
			(layer "B.Fab")
		)
		(fp_line
			(start 0.32512 -0.175006)
			(end -0.32512 -0.175006)
			(stroke
				(width 0.1)
				(type default)
			)
			(layer "B.Fab")
		)
		(fp_line
			(start -0.32512 0.175006)
			(end 0.32512 0.175006)
			(stroke
				(width 0.1)
				(type default)
			)
			(layer "B.Fab")
		)
		(fp_line
			(start -0.32512 -0.175006)
			(end -0.32512 0.175006)
			(stroke
				(width 0.1)
				(type default)
			)
			(layer "B.Fab")
		)
		(pad "1" smd rect
			(at 0.2667 0)
			(size 0.3048 0.381)
			(layers "B.Cu" "B.Mask" "B.Paste")
			(net "SMB_MUX_RT_ROM_SCL")
		)
		(pad "2" smd rect
			(at -0.2667 0 180)
			(size 0.3048 0.381)
			(layers "B.Cu" "B.Mask" "B.Paste")
			(net "SMB_MUX_RT_ROM_R1_SCL")
		)
	)
	(footprint ""
		(layer "B.Cu")
		(at 283.980636 -195.859146 180)
		(property "Reference" "R1676"
			(at 0 0 0)
			(layer "B.SilkS")
			(hide yes)
			(effects
				(font
					(size 1.27 1.27)
				)
				(justify mirror)
			)
		)
		(property "Value" ""
			(at 0 0 0)
			(layer "B.Fab")
			(effects
				(font
					(size 1.27 1.27)
				)
				(justify mirror)
			)
		)
		(duplicate_pad_numbers_are_jumpers no)
		(fp_line
			(start 0.7874 0.4064)
			(end 0.7874 -0.4064)
			(stroke
				(width 0.1524)
				(type default)
			)
			(layer "B.SilkS")
		)
		(fp_line
			(start 0.7874 -0.4064)
			(end -0.7874 -0.4064)
			(stroke
				(width 0.1524)
				(type default)
			)
			(layer "B.SilkS")
		)
		(fp_line
			(start -0.7874 0.4064)
			(end 0.7874 0.4064)
			(stroke
				(width 0.1524)
				(type default)
			)
			(layer "B.SilkS")
		)
		(fp_line
			(start -0.7874 -0.4064)
			(end -0.7874 0.4064)
			(stroke
				(width 0.1524)
				(type default)
			)
			(layer "B.SilkS")
		)
		(fp_line
			(start 0.67945 0.3048)
			(end 0.67945 -0.305054)
			(stroke
				(width 0.1)
				(type default)
			)
			(layer "B.Fab")
		)
		(fp_line
			(start 0.67945 -0.305054)
			(end 0.12065 -0.305054)
			(stroke
				(width 0.1)
				(type default)
			)
			(layer "B.Fab")
		)
		(fp_line
			(start 0.12065 0.3048)
			(end 0.67945 0.3048)
			(stroke
				(width 0.1)
				(type default)
			)
			(layer "B.Fab")
		)
		(fp_line
			(start 0.12065 0.2794)
			(end 0.12065 0.3048)
			(stroke
				(width 0.1)
				(type default)
			)
			(layer "B.Fab")
		)
		(fp_line
			(start 0.12065 -0.2794)
			(end -0.12065 -0.2794)
			(stroke
				(width 0.1)
				(type default)
			)
			(layer "B.Fab")
		)
		(fp_line
			(start 0.12065 -0.305054)
			(end 0.12065 -0.2794)
			(stroke
				(width 0.1)
				(type default)
			)
			(layer "B.Fab")
		)
		(fp_line
			(start -0.120396 0.3048)
			(end -0.120396 0.2794)
			(stroke
				(width 0.1)
				(type default)
			)
			(layer "B.Fab")
		)
		(fp_line
			(start -0.120396 0.2794)
			(end 0.12065 0.2794)
			(stroke
				(width 0.1)
				(type default)
			)
			(layer "B.Fab")
		)
		(fp_line
			(start -0.12065 -0.2794)
			(end -0.12065 -0.3048)
			(stroke
				(width 0.1)
				(type default)
			)
			(layer "B.Fab")
		)
		(fp_line
			(start -0.12065 -0.3048)
			(end -0.67945 -0.3048)
			(stroke
				(width 0.1)
				(type default)
			)
			(layer "B.Fab")
		)
		(fp_line
			(start -0.67945 0.3048)
			(end -0.120396 0.3048)
			(stroke
				(width 0.1)
				(type default)
			)
			(layer "B.Fab")
		)
		(fp_line
			(start -0.67945 -0.3048)
			(end -0.67945 0.3048)
			(stroke
				(width 0.1)
				(type default)
			)
			(layer "B.Fab")
		)
		(pad "1" smd circle
			(at 0.40005 0)
			(size 0 0)
			(layers "B.Cu" "B.Mask" "B.Paste")
			(net "I3C_SPD_DDRAF_CPU0_SDA")
		)
		(pad "2" smd circle
			(at -0.40005 0)
			(size 0 0)
			(layers "B.Cu" "B.Mask" "B.Paste")
			(net "I3C_SPD_DDRD_CPU0_SDA")
		)
	)
	(footprint ""
		(layer "B.Cu")
		(at 152.992836 -16.851122 -90)
		(property "Reference" "R3227"
			(at 0 0 90)
			(layer "B.SilkS")
			(hide yes)
			(effects
				(font
					(size 1.27 1.27)
				)
				(justify mirror)
			)
		)
		(property "Value" ""
			(at 0 0 90)
			(layer "B.Fab")
			(effects
				(font
					(size 1.27 1.27)
				)
				(justify mirror)
			)
		)
		(duplicate_pad_numbers_are_jumpers no)
		(fp_line
			(start -0.7874 0.4064)
			(end 0.7874 0.4064)
			(stroke
				(width 0.1524)
				(type default)
			)
			(layer "B.SilkS")
		)
		(fp_line
			(start 0.7874 0.4064)
			(end 0.7874 -0.4064)
			(stroke
				(width 0.1524)
				(type default)
			)
			(layer "B.SilkS")
		)
		(fp_line
			(start -0.7874 -0.4064)
			(end -0.7874 0.4064)
			(stroke
				(width 0.1524)
				(type default)
			)
			(layer "B.SilkS")
		)
		(fp_line
			(start 0.7874 -0.4064)
			(end -0.7874 -0.4064)
			(stroke
				(width 0.1524)
				(type default)
			)
			(layer "B.SilkS")
		)
		(fp_line
			(start -0.67945 0.3048)
			(end -0.120396 0.3048)
			(stroke
				(width 0.1)
				(type default)
			)
			(layer "B.Fab")
		)
		(fp_line
			(start -0.120396 0.3048)
			(end -0.120396 0.2794)
			(stroke
				(width 0.1)
				(type default)
			)
			(layer "B.Fab")
		)
		(fp_line
			(start 0.12065 0.3048)
			(end 0.67945 0.3048)
			(stroke
				(width 0.1)
				(type default)
			)
			(layer "B.Fab")
		)
		(fp_line
			(start 0.67945 0.3048)
			(end 0.67945 -0.305054)
			(stroke
				(width 0.1)
				(type default)
			)
			(layer "B.Fab")
		)
		(fp_line
			(start -0.120396 0.2794)
			(end 0.12065 0.2794)
			(stroke
				(width 0.1)
				(type default)
			)
			(layer "B.Fab")
		)
		(fp_line
			(start 0.12065 0.2794)
			(end 0.12065 0.3048)
			(stroke
				(width 0.1)
				(type default)
			)
			(layer "B.Fab")
		)
		(fp_line
			(start -0.12065 -0.2794)
			(end -0.12065 -0.3048)
			(stroke
				(width 0.1)
				(type default)
			)
			(layer "B.Fab")
		)
		(fp_line
			(start 0.12065 -0.2794)
			(end -0.12065 -0.2794)
			(stroke
				(width 0.1)
				(type default)
			)
			(layer "B.Fab")
		)
		(fp_line
			(start -0.67945 -0.3048)
			(end -0.67945 0.3048)
			(stroke
				(width 0.1)
				(type default)
			)
			(layer "B.Fab")
		)
		(fp_line
			(start -0.12065 -0.3048)
			(end -0.67945 -0.3048)
			(stroke
				(width 0.1)
				(type default)
			)
			(layer "B.Fab")
		)
		(fp_line
			(start 0.12065 -0.305054)
			(end 0.12065 -0.2794)
			(stroke
				(width 0.1)
				(type default)
			)
			(layer "B.Fab")
		)
		(fp_line
			(start 0.67945 -0.305054)
			(end 0.12065 -0.305054)
			(stroke
				(width 0.1)
				(type default)
			)
			(layer "B.Fab")
		)
		(pad "1" smd circle
			(at 0.40005 0 90)
			(size 0 0)
			(layers "B.Cu" "B.Mask" "B.Paste")
			(net "SMB_1_BMC_GPU_SDA")
		)
		(pad "2" smd circle
			(at -0.40005 0 90)
			(size 0 0)
			(layers "B.Cu" "B.Mask" "B.Paste")
			(net "P3V3_AUX")
		)
	)
)
